(kicad_pcb
	(version 20260206)
	(generator "pcbnew")
	(generator_version "10.0")
	(general
		(thickness 1.6)
		(legacy_teardrops no)
	)
	(paper "A4")
	(title_block
		(title "12092022_DA0F0TFB6D0_F0T_FAN_BOARD_MP5048_D_brd_v02_OCP.brd")
		(comment 1 "Grand Teton / footprints 825-830 of 924")
	)
	(layers
		(0 "F.Cu" signal "TOP")
		(4 "In1.Cu" signal "GND")
		(6 "In2.Cu" signal "IN1")
		(8 "In3.Cu" signal "IN2")
		(10 "In4.Cu" signal "GND1")
		(2 "B.Cu" signal "BOTTOM")
		(9 "F.Adhes" user "F.Adhesive")
		(11 "B.Adhes" user "B.Adhesive")
		(13 "F.Paste" user "Package Geometry/Pastemask Top")
		(15 "B.Paste" user "Package Geometry/Pastemask Bottom")
		(5 "F.SilkS" user "Ref Des/Silkscreen Top")
		(7 "B.SilkS" user "Ref Des/Silkscreen Bottom")
		(1 "F.Mask" user "Board Geometry/Soldermask Top")
		(3 "B.Mask" user "Board Geometry/Soldermask Bottom")
		(17 "Dwgs.User" user "User.Drawings")
		(19 "Cmts.User" user "User.Comments")
		(21 "Eco1.User" user "User.Eco1")
		(23 "Eco2.User" user "User.Eco2")
		(25 "Edge.Cuts" user "Board Geometry/Outline")
		(27 "Margin" user)
		(31 "F.CrtYd" user "Package Geometry/Place Bound Top")
		(29 "B.CrtYd" user "Package Geometry/Place Bound Bottom")
		(35 "F.Fab" user "Ref Des/Assembly Top")
		(33 "B.Fab" user "Ref Des/Assembly Bottom")
	)
	(footprint ""
		(layer "B.Cu")
		(at 5.070348 -237.718346)
		(property "Reference" "PC49"
			(at 0 0 0)
			(layer "B.SilkS")
			(hide yes)
			(effects
				(font
					(size 1.27 1.27)
				)
				(justify mirror)
			)
		)
		(property "Value" ""
			(at 0 0 0)
			(layer "B.Fab")
			(effects
				(font
					(size 1.27 1.27)
				)
				(justify mirror)
			)
		)
		(duplicate_pad_numbers_are_jumpers no)
		(fp_line
			(start -1.524 -0.762)
			(end -1.524 0.762)
			(stroke
				(width 0.1524)
				(type default)
			)
			(layer "B.SilkS")
		)
		(fp_line
			(start -1.524 0.762)
			(end 1.524 0.762)
			(stroke
				(width 0.1524)
				(type default)
			)
			(layer "B.SilkS")
		)
		(fp_line
			(start 1.524 -0.762)
			(end -1.524 -0.762)
			(stroke
				(width 0.1524)
				(type default)
			)
			(layer "B.SilkS")
		)
		(fp_line
			(start 1.524 0.762)
			(end 1.524 -0.762)
			(stroke
				(width 0.1524)
				(type default)
			)
			(layer "B.SilkS")
		)
		(fp_line
			(start -1.1049 -0.724916)
			(end 1.1049 -0.724916)
			(stroke
				(width 0.1)
				(type default)
			)
			(layer "B.Fab")
		)
		(fp_line
			(start -1.1049 0.724916)
			(end -1.1049 -0.724916)
			(stroke
				(width 0.1)
				(type default)
			)
			(layer "B.Fab")
		)
		(fp_line
			(start 1.1049 -0.724916)
			(end 1.1049 0.724916)
			(stroke
				(width 0.1)
				(type default)
			)
			(layer "B.Fab")
		)
		(fp_line
			(start 1.1049 0.724916)
			(end -1.1049 0.724916)
			(stroke
				(width 0.1)
				(type default)
			)
			(layer "B.Fab")
		)
		(pad "1" smd rect
			(at 0.889 0)
			(size 1.016 1.27)
			(layers "B.Cu" "B.Mask" "B.Paste")
			(net "P52V_FAN_6")
		)
		(pad "2" smd rect
			(at -0.889 0)
			(size 1.016 1.27)
			(layers "B.Cu" "B.Mask" "B.Paste")
			(net "GND")
		)
	)
	(footprint ""
		(layer "B.Cu")
		(at 40.513 -258.572 90)
		(property "Reference" "PC3"
			(at 0 0 90)
			(layer "B.SilkS")
			(hide yes)
			(effects
				(font
					(size 1.27 1.27)
				)
				(justify mirror)
			)
		)
		(property "Value" ""
			(at 0 0 90)
			(layer "B.Fab")
			(effects
				(font
					(size 1.27 1.27)
				)
				(justify mirror)
			)
		)
		(duplicate_pad_numbers_are_jumpers no)
		(fp_line
			(start 0.7874 -0.4064)
			(end -0.7874 -0.4064)
			(stroke
				(width 0.1524)
				(type default)
			)
			(layer "B.SilkS")
		)
		(fp_line
			(start -0.7874 -0.4064)
			(end -0.7874 0.4064)
			(stroke
				(width 0.1524)
				(type default)
			)
			(layer "B.SilkS")
		)
		(fp_line
			(start 0.7874 0.4064)
			(end 0.7874 -0.4064)
			(stroke
				(width 0.1524)
				(type default)
			)
			(layer "B.SilkS")
		)
		(fp_line
			(start -0.7874 0.4064)
			(end 0.7874 0.4064)
			(stroke
				(width 0.1524)
				(type default)
			)
			(layer "B.SilkS")
		)
		(fp_line
			(start 0.67945 -0.305054)
			(end 0.12065 -0.305054)
			(stroke
				(width 0.1)
				(type default)
			)
			(layer "B.Fab")
		)
		(fp_line
			(start 0.12065 -0.305054)
			(end 0.12065 -0.2794)
			(stroke
				(width 0.1)
				(type default)
			)
			(layer "B.Fab")
		)
		(fp_line
			(start -0.12065 -0.3048)
			(end -0.67945 -0.3048)
			(stroke
				(width 0.1)
				(type default)
			)
			(layer "B.Fab")
		)
		(fp_line
			(start -0.67945 -0.3048)
			(end -0.67945 0.3048)
			(stroke
				(width 0.1)
				(type default)
			)
			(layer "B.Fab")
		)
		(fp_line
			(start 0.12065 -0.2794)
			(end -0.12065 -0.2794)
			(stroke
				(width 0.1)
				(type default)
			)
			(layer "B.Fab")
		)
		(fp_line
			(start -0.12065 -0.2794)
			(end -0.12065 -0.3048)
			(stroke
				(width 0.1)
				(type default)
			)
			(layer "B.Fab")
		)
		(fp_line
			(start 0.12065 0.2794)
			(end 0.12065 0.3048)
			(stroke
				(width 0.1)
				(type default)
			)
			(layer "B.Fab")
		)
		(fp_line
			(start -0.120396 0.2794)
			(end 0.12065 0.2794)
			(stroke
				(width 0.1)
				(type default)
			)
			(layer "B.Fab")
		)
		(fp_line
			(start 0.67945 0.3048)
			(end 0.67945 -0.305054)
			(stroke
				(width 0.1)
				(type default)
			)
			(layer "B.Fab")
		)
		(fp_line
			(start 0.12065 0.3048)
			(end 0.67945 0.3048)
			(stroke
				(width 0.1)
				(type default)
			)
			(layer "B.Fab")
		)
		(fp_line
			(start -0.120396 0.3048)
			(end -0.120396 0.2794)
			(stroke
				(width 0.1)
				(type default)
			)
			(layer "B.Fab")
		)
		(fp_line
			(start -0.67945 0.3048)
			(end -0.120396 0.3048)
			(stroke
				(width 0.1)
				(type default)
			)
			(layer "B.Fab")
		)
		(pad "1" smd circle
			(at 0.40005 0 270)
			(size 0 0)
			(layers "B.Cu" "B.Mask" "B.Paste")
			(net "FAN_0_P3V_R")
		)
		(pad "2" smd circle
			(at -0.40005 0 270)
			(size 0 0)
			(layers "B.Cu" "B.Mask" "B.Paste")
			(net "GND")
		)
	)
	(footprint ""
		(layer "B.Cu")
		(at 5.50799 -263.017 -90)
		(property "Reference" "PD18"
			(at -2.54 -3.73634 270)
			(unlocked yes)
			(layer "B.SilkS")
			(effects
				(font
					(size 0.7874 0.5842)
					(thickness 0.1524)
				)
				(justify left mirror)
			)
		)
		(property "Value" ""
			(at 0 0 90)
			(layer "B.Fab")
			(effects
				(font
					(size 1.27 1.27)
				)
				(justify mirror)
			)
		)
		(duplicate_pad_numbers_are_jumpers no)
		(fp_line
			(start -5.536184 3.109976)
			(end -5.536184 -3.109976)
			(stroke
				(width 0.1524)
				(type default)
			)
			(layer "B.SilkS")
		)
		(fp_line
			(start 4.647184 3.109976)
			(end -5.536184 3.109976)
			(stroke
				(width 0.1524)
				(type default)
			)
			(layer "B.SilkS")
		)
		(fp_line
			(start 0.635 0.635)
			(end -0.635 -0.127)
			(stroke
				(width 0.1524)
				(type default)
			)
			(layer "B.SilkS")
		)
		(fp_line
			(start -0.635 -0.127)
			(end -1.397 -0.127)
			(stroke
				(width 0.1524)
				(type default)
			)
			(layer "B.SilkS")
		)
		(fp_line
			(start -0.635 -0.127)
			(end 0.635 -0.889)
			(stroke
				(width 0.1524)
				(type default)
			)
			(layer "B.SilkS")
		)
		(fp_line
			(start 1.397 -0.127)
			(end 0.635 -0.127)
			(stroke
				(width 0.1524)
				(type default)
			)
			(layer "B.SilkS")
		)
		(fp_line
			(start 0.635 -0.889)
			(end 0.635 0.635)
			(stroke
				(width 0.1524)
				(type default)
			)
			(layer "B.SilkS")
		)
		(fp_line
			(start -0.762 -1.143)
			(end -0.762 0.889)
			(stroke
				(width 0.1524)
				(type default)
			)
			(layer "B.SilkS")
		)
		(fp_line
			(start -5.536184 -3.109976)
			(end 4.647184 -3.109976)
			(stroke
				(width 0.1524)
				(type default)
			)
			(layer "B.SilkS")
		)
		(fp_line
			(start 4.647184 -3.109976)
			(end 4.647184 3.109976)
			(stroke
				(width 0.1524)
				(type default)
			)
			(layer "B.SilkS")
		)
		(fp_poly
			(pts
				(xy -5.5118 -3.0988) (xy -5.5118 3.1496) (xy -4.572 3.1496) (xy -4.572 -3.0988)
			)
			(stroke
				(width 0)
				(type default)
			)
			(fill yes)
			(layer "B.SilkS")
		)
		(fp_line
			(start -3.554984 3.109976)
			(end -3.554984 -3.109976)
			(stroke
				(width 0.1)
				(type default)
			)
			(layer "B.Fab")
		)
		(fp_line
			(start 3.554984 3.109976)
			(end -3.554984 3.109976)
			(stroke
				(width 0.1)
				(type default)
			)
			(layer "B.Fab")
		)
		(fp_line
			(start -3.554984 -3.109976)
			(end 3.554984 -3.109976)
			(stroke
				(width 0.1)
				(type default)
			)
			(layer "B.Fab")
		)
		(fp_line
			(start 3.554984 -3.109976)
			(end 3.554984 3.109976)
			(stroke
				(width 0.1)
				(type default)
			)
			(layer "B.Fab")
		)
		(fp_text user "+"
			(at 6.096 1.85674 270)
			(unlocked yes)
			(layer "B.SilkS")
			(effects
				(font
					(size 1.905 1.4224)
					(thickness 0.1524)
				)
				(justify left mirror)
			)
		)
		(fp_text user "-"
			(at -5.334 -2.08026 270)
			(unlocked yes)
			(layer "B.SilkS")
			(effects
				(font
					(size 1.905 1.4224)
					(thickness 0.1524)
				)
				(justify left mirror)
			)
		)
		(fp_text user "+"
			(at 6.1214 -0.32385 270)
			(unlocked yes)
			(layer "B.Fab")
			(effects
				(font
					(size 1.905 1.4224)
					(thickness 0.1524)
				)
				(justify left mirror)
			)
		)
		(fp_text user "-"
			(at -5.334 -0.34925 270)
			(unlocked yes)
			(layer "B.Fab")
			(effects
				(font
					(size 1.905 1.4224)
					(thickness 0.1524)
				)
				(justify left mirror)
			)
		)
		(pad "A" smd rect
			(at 3.299968 0 90)
			(size 2.413 3.302)
			(layers "B.Cu" "B.Mask" "B.Paste")
			(net "GND")
		)
		(pad "C" smd rect
			(at -3.299968 0 90)
			(size 2.413 3.302)
			(layers "B.Cu" "B.Mask" "B.Paste")
			(net "P52V_HSC")
		)
	)
	(footprint ""
		(layer "B.Cu")
		(at 42.418 -73.971912 -90)
		(property "Reference" "PC3120"
			(at 0 0 90)
			(layer "B.SilkS")
			(hide yes)
			(effects
				(font
					(size 1.27 1.27)
				)
				(justify mirror)
			)
		)
		(property "Value" ""
			(at 0 0 90)
			(layer "B.Fab")
			(effects
				(font
					(size 1.27 1.27)
				)
				(justify mirror)
			)
		)
		(duplicate_pad_numbers_are_jumpers no)
		(fp_line
			(start -0.7874 0.4064)
			(end 0.7874 0.4064)
			(stroke
				(width 0.1524)
				(type default)
			)
			(layer "B.SilkS")
		)
		(fp_line
			(start 0.7874 0.4064)
			(end 0.7874 -0.4064)
			(stroke
				(width 0.1524)
				(type default)
			)
			(layer "B.SilkS")
		)
		(fp_line
			(start -0.7874 -0.4064)
			(end -0.7874 0.4064)
			(stroke
				(width 0.1524)
				(type default)
			)
			(layer "B.SilkS")
		)
		(fp_line
			(start 0.7874 -0.4064)
			(end -0.7874 -0.4064)
			(stroke
				(width 0.1524)
				(type default)
			)
			(layer "B.SilkS")
		)
		(fp_line
			(start -0.67945 0.3048)
			(end -0.120396 0.3048)
			(stroke
				(width 0.1)
				(type default)
			)
			(layer "B.Fab")
		)
		(fp_line
			(start -0.120396 0.3048)
			(end -0.120396 0.2794)
			(stroke
				(width 0.1)
				(type default)
			)
			(layer "B.Fab")
		)
		(fp_line
			(start 0.12065 0.3048)
			(end 0.67945 0.3048)
			(stroke
				(width 0.1)
				(type default)
			)
			(layer "B.Fab")
		)
		(fp_line
			(start 0.67945 0.3048)
			(end 0.67945 -0.305054)
			(stroke
				(width 0.1)
				(type default)
			)
			(layer "B.Fab")
		)
		(fp_line
			(start -0.120396 0.2794)
			(end 0.12065 0.2794)
			(stroke
				(width 0.1)
				(type default)
			)
			(layer "B.Fab")
		)
		(fp_line
			(start 0.12065 0.2794)
			(end 0.12065 0.3048)
			(stroke
				(width 0.1)
				(type default)
			)
			(layer "B.Fab")
		)
		(fp_line
			(start -0.12065 -0.2794)
			(end -0.12065 -0.3048)
			(stroke
				(width 0.1)
				(type default)
			)
			(layer "B.Fab")
		)
		(fp_line
			(start 0.12065 -0.2794)
			(end -0.12065 -0.2794)
			(stroke
				(width 0.1)
				(type default)
			)
			(layer "B.Fab")
		)
		(fp_line
			(start -0.67945 -0.3048)
			(end -0.67945 0.3048)
			(stroke
				(width 0.1)
				(type default)
			)
			(layer "B.Fab")
		)
		(fp_line
			(start -0.12065 -0.3048)
			(end -0.67945 -0.3048)
			(stroke
				(width 0.1)
				(type default)
			)
			(layer "B.Fab")
		)
		(fp_line
			(start 0.12065 -0.305054)
			(end 0.12065 -0.2794)
			(stroke
				(width 0.1)
				(type default)
			)
			(layer "B.Fab")
		)
		(fp_line
			(start 0.67945 -0.305054)
			(end 0.12065 -0.305054)
			(stroke
				(width 0.1)
				(type default)
			)
			(layer "B.Fab")
		)
		(pad "1" smd circle
			(at 0.40005 0 90)
			(size 0 0)
			(layers "B.Cu" "B.Mask" "B.Paste")
			(net "GND")
		)
		(pad "2" smd circle
			(at -0.40005 0 90)
			(size 0 0)
			(layers "B.Cu" "B.Mask" "B.Paste")
			(net "FAN_2_CLREF")
		)
	)
	(footprint ""
		(layer "B.Cu")
		(at 37.587428 -263.017 90)
		(property "Reference" "PC8"
			(at 0 0 90)
			(layer "B.SilkS")
			(hide yes)
			(effects
				(font
					(size 1.27 1.27)
				)
				(justify mirror)
			)
		)
		(property "Value" ""
			(at 0 0 90)
			(layer "B.Fab")
			(effects
				(font
					(size 1.27 1.27)
				)
				(justify mirror)
			)
		)
		(duplicate_pad_numbers_are_jumpers no)
		(fp_line
			(start 1.524 -0.762)
			(end -1.524 -0.762)
			(stroke
				(width 0.1524)
				(type default)
			)
			(layer "B.SilkS")
		)
		(fp_line
			(start -1.524 -0.762)
			(end -1.524 0.762)
			(stroke
				(width 0.1524)
				(type default)
			)
			(layer "B.SilkS")
		)
		(fp_line
			(start 1.524 0.762)
			(end 1.524 -0.762)
			(stroke
				(width 0.1524)
				(type default)
			)
			(layer "B.SilkS")
		)
		(fp_line
			(start -1.524 0.762)
			(end 1.524 0.762)
			(stroke
				(width 0.1524)
				(type default)
			)
			(layer "B.SilkS")
		)
		(fp_line
			(start 1.1049 -0.724916)
			(end 1.1049 0.724916)
			(stroke
				(width 0.1)
				(type default)
			)
			(layer "B.Fab")
		)
		(fp_line
			(start -1.1049 -0.724916)
			(end 1.1049 -0.724916)
			(stroke
				(width 0.1)
				(type default)
			)
			(layer "B.Fab")
		)
		(fp_line
			(start 1.1049 0.724916)
			(end -1.1049 0.724916)
			(stroke
				(width 0.1)
				(type default)
			)
			(layer "B.Fab")
		)
		(fp_line
			(start -1.1049 0.724916)
			(end -1.1049 -0.724916)
			(stroke
				(width 0.1)
				(type default)
			)
			(layer "B.Fab")
		)
		(pad "1" smd rect
			(at 0.889 0 90)
			(size 1.016 1.27)
			(layers "B.Cu" "B.Mask" "B.Paste")
			(net "P52V_HSC")
		)
		(pad "2" smd rect
			(at -0.889 0 90)
			(size 1.016 1.27)
			(layers "B.Cu" "B.Mask" "B.Paste")
			(net "GND")
		)
	)
	(footprint ""
		(layer "B.Cu")
		(at 15.079218 -248.1326 90)
		(property "Reference" "PD17"
			(at -5.588 3.740912 270)
			(unlocked yes)
			(layer "B.SilkS")
			(effects
				(font
					(size 0.7874 0.5842)
					(thickness 0.1524)
				)
				(justify left mirror)
			)
		)
		(property "Value" ""
			(at 0 0 90)
			(layer "B.Fab")
			(effects
				(font
					(size 1.27 1.27)
				)
				(justify mirror)
			)
		)
		(duplicate_pad_numbers_are_jumpers no)
		(fp_line
			(start 4.647184 -3.109976)
			(end 4.647184 3.109976)
			(stroke
				(width 0.1524)
				(type default)
			)
			(layer "B.SilkS")
		)
		(fp_line
			(start -5.536184 -3.109976)
			(end 4.647184 -3.109976)
			(stroke
				(width 0.1524)
				(type default)
			)
			(layer "B.SilkS")
		)
		(fp_line
			(start -0.762 -1.143)
			(end -0.762 0.889)
			(stroke
				(width 0.1524)
				(type default)
			)
			(layer "B.SilkS")
		)
		(fp_line
			(start 0.635 -0.889)
			(end 0.635 0.635)
			(stroke
				(width 0.1524)
				(type default)
			)
			(layer "B.SilkS")
		)
		(fp_line
			(start 1.397 -0.127)
			(end 0.635 -0.127)
			(stroke
				(width 0.1524)
				(type default)
			)
			(layer "B.SilkS")
		)
		(fp_line
			(start -0.635 -0.127)
			(end 0.635 -0.889)
			(stroke
				(width 0.1524)
				(type default)
			)
			(layer "B.SilkS")
		)
		(fp_line
			(start -0.635 -0.127)
			(end -1.397 -0.127)
			(stroke
				(width 0.1524)
				(type default)
			)
			(layer "B.SilkS")
		)
		(fp_line
			(start 0.635 0.635)
			(end -0.635 -0.127)
			(stroke
				(width 0.1524)
				(type default)
			)
			(layer "B.SilkS")
		)
		(fp_line
			(start 4.647184 3.109976)
			(end -5.536184 3.109976)
			(stroke
				(width 0.1524)
				(type default)
			)
			(layer "B.SilkS")
		)
		(fp_line
			(start -5.536184 3.109976)
			(end -5.536184 -3.109976)
			(stroke
				(width 0.1524)
				(type default)
			)
			(layer "B.SilkS")
		)
		(fp_poly
			(pts
				(xy -5.5118 -3.0988) (xy -5.5118 3.1496) (xy -4.572 3.1496) (xy -4.572 -3.0988)
			)
			(stroke
				(width 0)
				(type default)
			)
			(fill yes)
			(layer "B.SilkS")
		)
		(fp_line
			(start 3.554984 -3.109976)
			(end 3.554984 3.109976)
			(stroke
				(width 0.1)
				(type default)
			)
			(layer "B.Fab")
		)
		(fp_line
			(start -3.554984 -3.109976)
			(end 3.554984 -3.109976)
			(stroke
				(width 0.1)
				(type default)
			)
			(layer "B.Fab")
		)
		(fp_line
			(start 3.554984 3.109976)
			(end -3.554984 3.109976)
			(stroke
				(width 0.1)
				(type default)
			)
			(layer "B.Fab")
		)
		(fp_line
			(start -3.554984 3.109976)
			(end -3.554984 -3.109976)
			(stroke
				(width 0.1)
				(type default)
			)
			(layer "B.Fab")
		)
		(fp_text user "+"
			(at 6.2484 -0.569468 90)
			(unlocked yes)
			(layer "B.SilkS")
			(effects
				(font
					(size 1.905 1.4224)
					(thickness 0.1524)
				)
				(justify left mirror)
			)
		)
		(fp_text user "-"
			(at -5.334 -0.34925 90)
			(unlocked yes)
			(layer "B.SilkS")
			(effects
				(font
					(size 1.905 1.4224)
					(thickness 0.1524)
				)
				(justify left mirror)
			)
		)
		(fp_text user "-"
			(at -5.334 -0.34925 90)
			(unlocked yes)
			(layer "B.Fab")
			(effects
				(font
					(size 1.905 1.4224)
					(thickness 0.1524)
				)
				(justify left mirror)
			)
		)
		(fp_text user "+"
			(at 6.1214 -0.32385 90)
			(unlocked yes)
			(layer "B.Fab")
			(effects
				(font
					(size 1.905 1.4224)
					(thickness 0.1524)
				)
				(justify left mirror)
			)
		)
		(pad "A" smd rect
			(at 3.299968 0 270)
			(size 2.413 3.302)
			(layers "B.Cu" "B.Mask" "B.Paste")
			(net "GND")
		)
		(pad "C" smd rect
			(at -3.299968 0 270)
			(size 2.413 3.302)
			(layers "B.Cu" "B.Mask" "B.Paste")
			(net "P52V_HSC")
		)
	)
)
